# S9S_MB_2U (Grand Teton) — schematic netlist excerpt (pin names and nets, part order shuffled) for the footprints in the layout excerpt that follows; sources: Cadence DE-HDL packaged netlist, KiCad conversion of 03242023_DA0F0TMBIJ0_F0T_Motherboard_J_brd_V01_OCP.brd

R4781  Q_RES  0 5% CHIP  pkg 0402LF  page 292 : A = PWRGD_PVCCINFAON_CPU1 ; B = PWRGD_PVCCINFAON_CPU1_R
C489  Q_CAP  47UF 2.5V 20% X6S  pkg C0603  page 78 : A = PVCCINFAON_CPU1 ; B = GND

(kicad_pcb
	(version 20260206)
	(generator "pcbnew")
	(generator_version "10.0")
	(general
		(thickness 1.6)
		(legacy_teardrops no)
	)
	(paper "A4")
	(title_block
		(title "03242023_DA0F0TMBIJ0_F0T_Motherboard_J_brd_V01_OCP.brd")
		(comment 1 "Grand Teton / footprints 4859-4860 of 6105")
	)
	(layers
		(0 "F.Cu" signal "TOP")
		(4 "In1.Cu" signal "GND")
		(6 "In2.Cu" signal "IN1")
		(8 "In3.Cu" signal "GND1")
		(10 "In4.Cu" signal "IN2")
		(12 "In5.Cu" signal "GND2")
		(14 "In6.Cu" signal "IN3")
		(16 "In7.Cu" signal "GND3")
		(18 "In8.Cu" signal "VCC")
		(20 "In9.Cu" signal "VCC1")
		(22 "In10.Cu" signal "GND4")
		(24 "In11.Cu" signal "IN4")
		(26 "In12.Cu" signal "GND5")
		(28 "In13.Cu" signal "IN5")
		(30 "In14.Cu" signal "GND6")
		(32 "In15.Cu" signal "IN6")
		(34 "In16.Cu" signal "GND7")
		(2 "B.Cu" signal "BOTTOM")
		(9 "F.Adhes" user "F.Adhesive")
		(11 "B.Adhes" user "B.Adhesive")
		(13 "F.Paste" user "Package Geometry/Pastemask Top")
		(15 "B.Paste" user "Package Geometry/Pastemask Bottom")
		(5 "F.SilkS" user "Ref Des/Silkscreen Top")
		(7 "B.SilkS" user "Ref Des/Silkscreen Bottom")
		(1 "F.Mask" user "Board Geometry/Soldermask Top")
		(3 "B.Mask" user "Board Geometry/Soldermask Bottom")
		(17 "Dwgs.User" user "User.Drawings")
		(19 "Cmts.User" user "User.Comments")
		(21 "Eco1.User" user "User.Eco1")
		(23 "Eco2.User" user "User.Eco2")
		(25 "Edge.Cuts" user "Board Geometry/Outline")
		(27 "Margin" user)
		(31 "F.CrtYd" user "Package Geometry/Place Bound Top")
		(29 "B.CrtYd" user "Package Geometry/Place Bound Bottom")
		(35 "F.Fab" user "Ref Des/Assembly Top")
		(33 "B.Fab" user "Ref Des/Assembly Bottom")
	)
	(footprint ""
		(layer "B.Cu")
		(at 36.968938 -126.40056)
		(property "Reference" "R4781"
			(at 0 0 0)
			(layer "B.SilkS")
			(hide yes)
			(effects
				(font
					(size 1.27 1.27)
				)
				(justify mirror)
			)
		)
		(property "Value" ""
			(at 0 0 0)
			(layer "B.Fab")
			(effects
				(font
					(size 1.27 1.27)
				)
				(justify mirror)
			)
		)
		(duplicate_pad_numbers_are_jumpers no)
		(fp_line
			(start -0.7874 -0.4064)
			(end -0.7874 0.4064)
			(stroke
				(width 0.1524)
				(type default)
			)
			(layer "B.SilkS")
		)
		(fp_line
			(start -0.7874 0.4064)
			(end 0.7874 0.4064)
			(stroke
				(width 0.1524)
				(type default)
			)
			(layer "B.SilkS")
		)
		(fp_line
			(start 0.7874 -0.4064)
			(end -0.7874 -0.4064)
			(stroke
				(width 0.1524)
				(type default)
			)
			(layer "B.SilkS")
		)
		(fp_line
			(start 0.7874 0.4064)
			(end 0.7874 -0.4064)
			(stroke
				(width 0.1524)
				(type default)
			)
			(layer "B.SilkS")
		)
		(fp_line
			(start -0.67945 -0.3048)
			(end -0.67945 0.3048)
			(stroke
				(width 0.1)
				(type default)
			)
			(layer "B.Fab")
		)
		(fp_line
			(start -0.67945 0.3048)
			(end -0.120396 0.3048)
			(stroke
				(width 0.1)
				(type default)
			)
			(layer "B.Fab")
		)
		(fp_line
			(start -0.12065 -0.3048)
			(end -0.67945 -0.3048)
			(stroke
				(width 0.1)
				(type default)
			)
			(layer "B.Fab")
		)
		(fp_line
			(start -0.12065 -0.2794)
			(end -0.12065 -0.3048)
			(stroke
				(width 0.1)
				(type default)
			)
			(layer "B.Fab")
		)
		(fp_line
			(start -0.120396 0.2794)
			(end 0.12065 0.2794)
			(stroke
				(width 0.1)
				(type default)
			)
			(layer "B.Fab")
		)
		(fp_line
			(start -0.120396 0.3048)
			(end -0.120396 0.2794)
			(stroke
				(width 0.1)
				(type default)
			)
			(layer "B.Fab")
		)
		(fp_line
			(start 0.12065 -0.305054)
			(end 0.12065 -0.2794)
			(stroke
				(width 0.1)
				(type default)
			)
			(layer "B.Fab")
		)
		(fp_line
			(start 0.12065 -0.2794)
			(end -0.12065 -0.2794)
			(stroke
				(width 0.1)
				(type default)
			)
			(layer "B.Fab")
		)
		(fp_line
			(start 0.12065 0.2794)
			(end 0.12065 0.3048)
			(stroke
				(width 0.1)
				(type default)
			)
			(layer "B.Fab")
		)
		(fp_line
			(start 0.12065 0.3048)
			(end 0.67945 0.3048)
			(stroke
				(width 0.1)
				(type default)
			)
			(layer "B.Fab")
		)
		(fp_line
			(start 0.67945 -0.305054)
			(end 0.12065 -0.305054)
			(stroke
				(width 0.1)
				(type default)
			)
			(layer "B.Fab")
		)
		(fp_line
			(start 0.67945 0.3048)
			(end 0.67945 -0.305054)
			(stroke
				(width 0.1)
				(type default)
			)
			(layer "B.Fab")
		)
		(pad "1" smd circle
			(at 0.40005 0 180)
			(size 0 0)
			(layers "B.Cu" "B.Mask" "B.Paste")
			(net "PWRGD_PVCCINFAON_CPU1")
		)
		(pad "2" smd circle
			(at -0.40005 0 180)
			(size 0 0)
			(layers "B.Cu" "B.Mask" "B.Paste")
			(net "PWRGD_PVCCINFAON_CPU1_R")
		)
	)
	(footprint ""
		(layer "B.Cu")
		(at 117.87632 -237.709456 -90)
		(property "Reference" "C489"
			(at 0 0 90)
			(layer "B.SilkS")
			(hide yes)
			(effects
				(font
					(size 1.27 1.27)
				)
				(justify mirror)
			)
		)
		(property "Value" ""
			(at 0 0 90)
			(layer "B.Fab")
			(effects
				(font
					(size 1.27 1.27)
				)
				(justify mirror)
			)
		)
		(duplicate_pad_numbers_are_jumpers no)
		(fp_line
			(start -1.2954 0.5842)
			(end 1.2954 0.5842)
			(stroke
				(width 0.1524)
				(type default)
			)
			(layer "B.SilkS")
		)
		(fp_line
			(start 1.2954 0.5842)
			(end 1.2954 -0.5842)
			(stroke
				(width 0.1524)
				(type default)
			)
			(layer "B.SilkS")
		)
		(fp_line
			(start -1.2954 -0.5842)
			(end -1.2954 0.5842)
			(stroke
				(width 0.1524)
				(type default)
			)
			(layer "B.SilkS")
		)
		(fp_line
			(start 0 -0.5842)
			(end 0 0.5842)
			(stroke
				(width 0.1524)
				(type default)
			)
			(layer "B.SilkS")
		)
		(fp_line
			(start 1.2954 -0.5842)
			(end -1.2954 -0.5842)
			(stroke
				(width 0.1524)
				(type default)
			)
			(layer "B.SilkS")
		)
		(fp_line
			(start -0.8636 0.4572)
			(end 0.8636 0.4572)
			(stroke
				(width 0.1)
				(type default)
			)
			(layer "B.Fab")
		)
		(fp_line
			(start 0.8636 0.4572)
			(end 0.8636 0.4064)
			(stroke
				(width 0.1)
				(type default)
			)
			(layer "B.Fab")
		)
		(fp_line
			(start -1.1938 0.4064)
			(end -0.8636 0.4064)
			(stroke
				(width 0.1)
				(type default)
			)
			(layer "B.Fab")
		)
		(fp_line
			(start -0.8636 0.4064)
			(end -0.8636 0.4572)
			(stroke
				(width 0.1)
				(type default)
			)
			(layer "B.Fab")
		)
		(fp_line
			(start 0.8636 0.4064)
			(end 1.1938 0.4064)
			(stroke
				(width 0.1)
				(type default)
			)
			(layer "B.Fab")
		)
		(fp_line
			(start 1.1938 0.4064)
			(end 1.1938 -0.4064)
			(stroke
				(width 0.1)
				(type default)
			)
			(layer "B.Fab")
		)
		(fp_line
			(start -1.1938 -0.4064)
			(end -1.1938 0.4064)
			(stroke
				(width 0.1)
				(type default)
			)
			(layer "B.Fab")
		)
		(fp_line
			(start -0.8636 -0.4064)
			(end -1.1938 -0.4064)
			(stroke
				(width 0.1)
				(type default)
			)
			(layer "B.Fab")
		)
		(fp_line
			(start 0.8636 -0.4064)
			(end 0.8636 -0.4572)
			(stroke
				(width 0.1)
				(type default)
			)
			(layer "B.Fab")
		)
		(fp_line
			(start 1.1938 -0.4064)
			(end 0.8636 -0.4064)
			(stroke
				(width 0.1)
				(type default)
			)
			(layer "B.Fab")
		)
		(fp_line
			(start -0.8636 -0.4572)
			(end -0.8636 -0.4064)
			(stroke
				(width 0.1)
				(type default)
			)
			(layer "B.Fab")
		)
		(fp_line
			(start 0.8636 -0.4572)
			(end -0.8636 -0.4572)
			(stroke
				(width 0.1)
				(type default)
			)
			(layer "B.Fab")
		)
		(pad "1" smd rect
			(at 0.7366 0 180)
			(size 0.7112 0.8128)
			(layers "B.Cu" "B.Mask" "B.Paste")
			(net "PVCCINFAON_CPU1")
		)
		(pad "2" smd rect
			(at -0.7366 0 180)
			(size 0.7112 0.8128)
			(layers "B.Cu" "B.Mask" "B.Paste")
			(net "GND")
		)
	)
)
